(kicad_pcb
	(version 20260206)
	(generator "pcbnew")
	(generator_version "10.0")
	(general
		(thickness 1.6)
		(legacy_teardrops no)
	)
	(paper "A4")
	(title_block
		(title "03242023_DA0F0TMBIJ0_F0T_Motherboard_J_brd_V01_OCP.brd")
		(comment 1 "Grand Teton / footprints 3870-3875 of 6105")
	)
	(layers
		(0 "F.Cu" signal "TOP")
		(4 "In1.Cu" signal "GND")
		(6 "In2.Cu" signal "IN1")
		(8 "In3.Cu" signal "GND1")
		(10 "In4.Cu" signal "IN2")
		(12 "In5.Cu" signal "GND2")
		(14 "In6.Cu" signal "IN3")
		(16 "In7.Cu" signal "GND3")
		(18 "In8.Cu" signal "VCC")
		(20 "In9.Cu" signal "VCC1")
		(22 "In10.Cu" signal "GND4")
		(24 "In11.Cu" signal "IN4")
		(26 "In12.Cu" signal "GND5")
		(28 "In13.Cu" signal "IN5")
		(30 "In14.Cu" signal "GND6")
		(32 "In15.Cu" signal "IN6")
		(34 "In16.Cu" signal "GND7")
		(2 "B.Cu" signal "BOTTOM")
		(9 "F.Adhes" user "F.Adhesive")
		(11 "B.Adhes" user "B.Adhesive")
		(13 "F.Paste" user "Package Geometry/Pastemask Top")
		(15 "B.Paste" user "Package Geometry/Pastemask Bottom")
		(5 "F.SilkS" user "Ref Des/Silkscreen Top")
		(7 "B.SilkS" user "Ref Des/Silkscreen Bottom")
		(1 "F.Mask" user "Board Geometry/Soldermask Top")
		(3 "B.Mask" user "Board Geometry/Soldermask Bottom")
		(17 "Dwgs.User" user "User.Drawings")
		(19 "Cmts.User" user "User.Comments")
		(21 "Eco1.User" user "User.Eco1")
		(23 "Eco2.User" user "User.Eco2")
		(25 "Edge.Cuts" user "Board Geometry/Outline")
		(27 "Margin" user)
		(31 "F.CrtYd" user "Package Geometry/Place Bound Top")
		(29 "B.CrtYd" user "Package Geometry/Place Bound Bottom")
		(35 "F.Fab" user "Ref Des/Assembly Top")
		(33 "B.Fab" user "Ref Des/Assembly Bottom")
	)
	(footprint ""
		(layer "F.Cu")
		(at 420.473632 -170.126914)
		(property "Reference" "PR1774"
			(at 0 0 0)
			(layer "F.SilkS")
			(hide yes)
			(effects
				(font
					(size 1.27 1.27)
				)
			)
		)
		(property "Value" ""
			(at 0 0 0)
			(layer "F.Fab")
			(effects
				(font
					(size 1.27 1.27)
				)
			)
		)
		(duplicate_pad_numbers_are_jumpers no)
		(fp_line
			(start -0.7874 -0.4064)
			(end 0.7874 -0.4064)
			(stroke
				(width 0.1524)
				(type default)
			)
			(layer "F.SilkS")
		)
		(fp_line
			(start -0.7874 0.4064)
			(end -0.7874 -0.4064)
			(stroke
				(width 0.1524)
				(type default)
			)
			(layer "F.SilkS")
		)
		(fp_line
			(start 0.7874 -0.4064)
			(end 0.7874 0.4064)
			(stroke
				(width 0.1524)
				(type default)
			)
			(layer "F.SilkS")
		)
		(fp_line
			(start 0.7874 0.4064)
			(end -0.7874 0.4064)
			(stroke
				(width 0.1524)
				(type default)
			)
			(layer "F.SilkS")
		)
		(fp_line
			(start -0.67945 -0.305054)
			(end -0.12065 -0.305054)
			(stroke
				(width 0.1)
				(type default)
			)
			(layer "F.Fab")
		)
		(fp_line
			(start -0.67945 0.3048)
			(end -0.67945 -0.305054)
			(stroke
				(width 0.1)
				(type default)
			)
			(layer "F.Fab")
		)
		(fp_line
			(start -0.12065 -0.305054)
			(end -0.12065 -0.2794)
			(stroke
				(width 0.1)
				(type default)
			)
			(layer "F.Fab")
		)
		(fp_line
			(start -0.12065 -0.2794)
			(end 0.12065 -0.2794)
			(stroke
				(width 0.1)
				(type default)
			)
			(layer "F.Fab")
		)
		(fp_line
			(start -0.12065 0.2794)
			(end -0.12065 0.3048)
			(stroke
				(width 0.1)
				(type default)
			)
			(layer "F.Fab")
		)
		(fp_line
			(start -0.12065 0.3048)
			(end -0.67945 0.3048)
			(stroke
				(width 0.1)
				(type default)
			)
			(layer "F.Fab")
		)
		(fp_line
			(start 0.120396 0.2794)
			(end -0.12065 0.2794)
			(stroke
				(width 0.1)
				(type default)
			)
			(layer "F.Fab")
		)
		(fp_line
			(start 0.120396 0.3048)
			(end 0.120396 0.2794)
			(stroke
				(width 0.1)
				(type default)
			)
			(layer "F.Fab")
		)
		(fp_line
			(start 0.12065 -0.3048)
			(end 0.67945 -0.3048)
			(stroke
				(width 0.1)
				(type default)
			)
			(layer "F.Fab")
		)
		(fp_line
			(start 0.12065 -0.2794)
			(end 0.12065 -0.3048)
			(stroke
				(width 0.1)
				(type default)
			)
			(layer "F.Fab")
		)
		(fp_line
			(start 0.67945 -0.3048)
			(end 0.67945 0.3048)
			(stroke
				(width 0.1)
				(type default)
			)
			(layer "F.Fab")
		)
		(fp_line
			(start 0.67945 0.3048)
			(end 0.120396 0.3048)
			(stroke
				(width 0.1)
				(type default)
			)
			(layer "F.Fab")
		)
		(pad "1" smd circle
			(at -0.40005 0)
			(size 0 0)
			(layers "F.Cu" "F.Mask" "F.Paste")
			(net "SW_PVCCINFAON_CPU0_BOOT1")
		)
		(pad "2" smd circle
			(at 0.40005 0)
			(size 0 0)
			(layers "F.Cu" "F.Mask" "F.Paste")
			(net "SW_PVCCINFAON_CPU0_BOOT1_R")
		)
	)
	(footprint ""
		(layer "F.Cu")
		(at 101.833934 -396.44574 180)
		(property "Reference" "R3493"
			(at 0 0 180)
			(layer "F.SilkS")
			(hide yes)
			(effects
				(font
					(size 1.27 1.27)
				)
			)
		)
		(property "Value" ""
			(at 0 0 180)
			(layer "F.Fab")
			(effects
				(font
					(size 1.27 1.27)
				)
			)
		)
		(duplicate_pad_numbers_are_jumpers no)
		(fp_line
			(start 0.7874 0.4064)
			(end -0.7874 0.4064)
			(stroke
				(width 0.1524)
				(type default)
			)
			(layer "F.SilkS")
		)
		(fp_line
			(start 0.7874 -0.4064)
			(end 0.7874 0.4064)
			(stroke
				(width 0.1524)
				(type default)
			)
			(layer "F.SilkS")
		)
		(fp_line
			(start -0.7874 0.4064)
			(end -0.7874 -0.4064)
			(stroke
				(width 0.1524)
				(type default)
			)
			(layer "F.SilkS")
		)
		(fp_line
			(start -0.7874 -0.4064)
			(end 0.7874 -0.4064)
			(stroke
				(width 0.1524)
				(type default)
			)
			(layer "F.SilkS")
		)
		(fp_line
			(start 0.67945 0.3048)
			(end 0.120396 0.3048)
			(stroke
				(width 0.1)
				(type default)
			)
			(layer "F.Fab")
		)
		(fp_line
			(start 0.67945 -0.3048)
			(end 0.67945 0.3048)
			(stroke
				(width 0.1)
				(type default)
			)
			(layer "F.Fab")
		)
		(fp_line
			(start 0.12065 -0.2794)
			(end 0.12065 -0.3048)
			(stroke
				(width 0.1)
				(type default)
			)
			(layer "F.Fab")
		)
		(fp_line
			(start 0.12065 -0.3048)
			(end 0.67945 -0.3048)
			(stroke
				(width 0.1)
				(type default)
			)
			(layer "F.Fab")
		)
		(fp_line
			(start 0.120396 0.3048)
			(end 0.120396 0.2794)
			(stroke
				(width 0.1)
				(type default)
			)
			(layer "F.Fab")
		)
		(fp_line
			(start 0.120396 0.2794)
			(end -0.12065 0.2794)
			(stroke
				(width 0.1)
				(type default)
			)
			(layer "F.Fab")
		)
		(fp_line
			(start -0.12065 0.3048)
			(end -0.67945 0.3048)
			(stroke
				(width 0.1)
				(type default)
			)
			(layer "F.Fab")
		)
		(fp_line
			(start -0.12065 0.2794)
			(end -0.12065 0.3048)
			(stroke
				(width 0.1)
				(type default)
			)
			(layer "F.Fab")
		)
		(fp_line
			(start -0.12065 -0.2794)
			(end 0.12065 -0.2794)
			(stroke
				(width 0.1)
				(type default)
			)
			(layer "F.Fab")
		)
		(fp_line
			(start -0.12065 -0.305054)
			(end -0.12065 -0.2794)
			(stroke
				(width 0.1)
				(type default)
			)
			(layer "F.Fab")
		)
		(fp_line
			(start -0.67945 0.3048)
			(end -0.67945 -0.305054)
			(stroke
				(width 0.1)
				(type default)
			)
			(layer "F.Fab")
		)
		(fp_line
			(start -0.67945 -0.305054)
			(end -0.12065 -0.305054)
			(stroke
				(width 0.1)
				(type default)
			)
			(layer "F.Fab")
		)
		(pad "1" smd circle
			(at -0.40005 0 180)
			(size 0 0)
			(layers "F.Cu" "F.Mask" "F.Paste")
			(net "GPU_FPGA_EROT_RST_BUF_R_N")
		)
		(pad "2" smd circle
			(at 0.40005 0 180)
			(size 0 0)
			(layers "F.Cu" "F.Mask" "F.Paste")
			(net "GND")
		)
	)
	(footprint ""
		(layer "F.Cu")
		(at 352.281744 -240.276888 90)
		(property "Reference" "C418"
			(at 0 0 90)
			(layer "F.SilkS")
			(hide yes)
			(effects
				(font
					(size 1.27 1.27)
				)
			)
		)
		(property "Value" ""
			(at 0 0 90)
			(layer "F.Fab")
			(effects
				(font
					(size 1.27 1.27)
				)
			)
		)
		(duplicate_pad_numbers_are_jumpers no)
		(fp_line
			(start 0.7874 -0.4064)
			(end 0.7874 0.4064)
			(stroke
				(width 0.1524)
				(type default)
			)
			(layer "F.SilkS")
		)
		(fp_line
			(start -0.7874 -0.4064)
			(end 0.7874 -0.4064)
			(stroke
				(width 0.1524)
				(type default)
			)
			(layer "F.SilkS")
		)
		(fp_line
			(start 0.7874 0.4064)
			(end -0.7874 0.4064)
			(stroke
				(width 0.1524)
				(type default)
			)
			(layer "F.SilkS")
		)
		(fp_line
			(start -0.7874 0.4064)
			(end -0.7874 -0.4064)
			(stroke
				(width 0.1524)
				(type default)
			)
			(layer "F.SilkS")
		)
		(fp_line
			(start -0.12065 -0.305054)
			(end -0.12065 -0.2794)
			(stroke
				(width 0.1)
				(type default)
			)
			(layer "F.Fab")
		)
		(fp_line
			(start -0.67945 -0.305054)
			(end -0.12065 -0.305054)
			(stroke
				(width 0.1)
				(type default)
			)
			(layer "F.Fab")
		)
		(fp_line
			(start 0.67945 -0.3048)
			(end 0.67945 0.3048)
			(stroke
				(width 0.1)
				(type default)
			)
			(layer "F.Fab")
		)
		(fp_line
			(start 0.12065 -0.3048)
			(end 0.67945 -0.3048)
			(stroke
				(width 0.1)
				(type default)
			)
			(layer "F.Fab")
		)
		(fp_line
			(start 0.12065 -0.2794)
			(end 0.12065 -0.3048)
			(stroke
				(width 0.1)
				(type default)
			)
			(layer "F.Fab")
		)
		(fp_line
			(start -0.12065 -0.2794)
			(end 0.12065 -0.2794)
			(stroke
				(width 0.1)
				(type default)
			)
			(layer "F.Fab")
		)
		(fp_line
			(start 0.120396 0.2794)
			(end -0.12065 0.2794)
			(stroke
				(width 0.1)
				(type default)
			)
			(layer "F.Fab")
		)
		(fp_line
			(start -0.12065 0.2794)
			(end -0.12065 0.3048)
			(stroke
				(width 0.1)
				(type default)
			)
			(layer "F.Fab")
		)
		(fp_line
			(start 0.67945 0.3048)
			(end 0.120396 0.3048)
			(stroke
				(width 0.1)
				(type default)
			)
			(layer "F.Fab")
		)
		(fp_line
			(start 0.120396 0.3048)
			(end 0.120396 0.2794)
			(stroke
				(width 0.1)
				(type default)
			)
			(layer "F.Fab")
		)
		(fp_line
			(start -0.12065 0.3048)
			(end -0.67945 0.3048)
			(stroke
				(width 0.1)
				(type default)
			)
			(layer "F.Fab")
		)
		(fp_line
			(start -0.67945 0.3048)
			(end -0.67945 -0.305054)
			(stroke
				(width 0.1)
				(type default)
			)
			(layer "F.Fab")
		)
		(pad "1" smd circle
			(at -0.40005 0 90)
			(size 0 0)
			(layers "F.Cu" "F.Mask" "F.Paste")
			(net "PVCCFA_EHV_FIVRA_CPU0")
		)
		(pad "2" smd circle
			(at 0.40005 0 90)
			(size 0 0)
			(layers "F.Cu" "F.Mask" "F.Paste")
			(net "GND")
		)
	)
	(footprint ""
		(layer "F.Cu")
		(at 188.0108 -93.91015 -90)
		(property "Reference" "R1318"
			(at 0 0 270)
			(layer "F.SilkS")
			(hide yes)
			(effects
				(font
					(size 1.27 1.27)
				)
			)
		)
		(property "Value" ""
			(at 0 0 270)
			(layer "F.Fab")
			(effects
				(font
					(size 1.27 1.27)
				)
			)
		)
		(duplicate_pad_numbers_are_jumpers no)
		(fp_line
			(start -0.7874 0.4064)
			(end -0.7874 -0.4064)
			(stroke
				(width 0.1524)
				(type default)
			)
			(layer "F.SilkS")
		)
		(fp_line
			(start 0.7874 0.4064)
			(end -0.7874 0.4064)
			(stroke
				(width 0.1524)
				(type default)
			)
			(layer "F.SilkS")
		)
		(fp_line
			(start -0.7874 -0.4064)
			(end 0.7874 -0.4064)
			(stroke
				(width 0.1524)
				(type default)
			)
			(layer "F.SilkS")
		)
		(fp_line
			(start 0.7874 -0.4064)
			(end 0.7874 0.4064)
			(stroke
				(width 0.1524)
				(type default)
			)
			(layer "F.SilkS")
		)
		(fp_line
			(start -0.67945 0.3048)
			(end -0.67945 -0.305054)
			(stroke
				(width 0.1)
				(type default)
			)
			(layer "F.Fab")
		)
		(fp_line
			(start -0.12065 0.3048)
			(end -0.67945 0.3048)
			(stroke
				(width 0.1)
				(type default)
			)
			(layer "F.Fab")
		)
		(fp_line
			(start 0.120396 0.3048)
			(end 0.120396 0.2794)
			(stroke
				(width 0.1)
				(type default)
			)
			(layer "F.Fab")
		)
		(fp_line
			(start 0.67945 0.3048)
			(end 0.120396 0.3048)
			(stroke
				(width 0.1)
				(type default)
			)
			(layer "F.Fab")
		)
		(fp_line
			(start -0.12065 0.2794)
			(end -0.12065 0.3048)
			(stroke
				(width 0.1)
				(type default)
			)
			(layer "F.Fab")
		)
		(fp_line
			(start 0.120396 0.2794)
			(end -0.12065 0.2794)
			(stroke
				(width 0.1)
				(type default)
			)
			(layer "F.Fab")
		)
		(fp_line
			(start -0.12065 -0.2794)
			(end 0.12065 -0.2794)
			(stroke
				(width 0.1)
				(type default)
			)
			(layer "F.Fab")
		)
		(fp_line
			(start 0.12065 -0.2794)
			(end 0.12065 -0.3048)
			(stroke
				(width 0.1)
				(type default)
			)
			(layer "F.Fab")
		)
		(fp_line
			(start 0.12065 -0.3048)
			(end 0.67945 -0.3048)
			(stroke
				(width 0.1)
				(type default)
			)
			(layer "F.Fab")
		)
		(fp_line
			(start 0.67945 -0.3048)
			(end 0.67945 0.3048)
			(stroke
				(width 0.1)
				(type default)
			)
			(layer "F.Fab")
		)
		(fp_line
			(start -0.67945 -0.305054)
			(end -0.12065 -0.305054)
			(stroke
				(width 0.1)
				(type default)
			)
			(layer "F.Fab")
		)
		(fp_line
			(start -0.12065 -0.305054)
			(end -0.12065 -0.2794)
			(stroke
				(width 0.1)
				(type default)
			)
			(layer "F.Fab")
		)
		(pad "1" smd circle
			(at -0.40005 0 270)
			(size 0 0)
			(layers "F.Cu" "F.Mask" "F.Paste")
			(net "FM_THERMTRIP_DLY_LVC1_R_N")
		)
		(pad "2" smd circle
			(at 0.40005 0 270)
			(size 0 0)
			(layers "F.Cu" "F.Mask" "F.Paste")
			(net "FM_THERMTRIP_DLY_LVC1_N")
		)
	)
	(footprint ""
		(layer "F.Cu")
		(at 323.342 -31.0642 135)
		(property "Reference" "Y1"
			(at -0.163979 -3.010002 0)
			(unlocked yes)
			(layer "F.SilkS")
			(effects
				(font
					(size 0.7874 0.5842)
					(thickness 0.1524)
				)
				(justify left)
			)
		)
		(property "Value" ""
			(at 0 0 135)
			(layer "F.Fab")
			(effects
				(font
					(size 1.27 1.27)
				)
			)
		)
		(duplicate_pad_numbers_are_jumpers no)
		(fp_line
			(start 1.904892 -1.04135)
			(end -1.904892 -1.04135)
			(stroke
				(width 0.1524)
				(type default)
			)
			(layer "F.SilkS")
		)
		(fp_line
			(start 1.904892 1.04135)
			(end 1.904892 -1.04135)
			(stroke
				(width 0.1524)
				(type default)
			)
			(layer "F.SilkS")
		)
		(fp_line
			(start -1.904892 -1.04135)
			(end -1.904892 1.04135)
			(stroke
				(width 0.1524)
				(type default)
			)
			(layer "F.SilkS")
		)
		(fp_line
			(start -1.904892 1.04135)
			(end 1.904892 1.04135)
			(stroke
				(width 0.1524)
				(type default)
			)
			(layer "F.SilkS")
		)
		(fp_line
			(start 1.650032 -0.824926)
			(end -1.650032 -0.824926)
			(stroke
				(width 0.1)
				(type default)
			)
			(layer "F.Fab")
		)
		(fp_line
			(start 1.650032 0.824926)
			(end 1.650032 -0.824926)
			(stroke
				(width 0.1)
				(type default)
			)
			(layer "F.Fab")
		)
		(fp_line
			(start -1.650032 -0.824926)
			(end -1.650032 0.824926)
			(stroke
				(width 0.1)
				(type default)
			)
			(layer "F.Fab")
		)
		(fp_line
			(start -1.650032 0.824926)
			(end 1.650032 0.824926)
			(stroke
				(width 0.1)
				(type default)
			)
			(layer "F.Fab")
		)
		(pad "1" smd rect
			(at -1.249934 0 135)
			(size 1.016 1.8034)
			(layers "F.Cu" "F.Mask" "F.Paste")
			(net "XTAL_PCH_RTC2_R")
		)
		(pad "2" smd rect
			(at 1.249934 0 315)
			(size 1.016 1.8034)
			(layers "F.Cu" "F.Mask" "F.Paste")
			(net "XTAL_PCH_RTC1")
		)
		(zone
			(layer "F.Cu")
			(hatch none 0.5)
			(connect_pads
				(clearance 0)
			)
			(min_thickness 0.25)
			(keepout
				(tracks not_allowed)
				(vias allowed)
				(pads allowed)
				(copperpour not_allowed)
				(footprints allowed)
			)
			(placement
				(enabled no)
				(sheetname "")
			)
			(fill
				(thermal_gap 0.5)
				(thermal_bridge_width 0.5)
				(island_removal_mode 0)
			)
			(polygon
				(pts
					(xy 323.157088 -29.901896) (xy 324.504304 -31.249112) (xy 323.526912 -32.226504) (xy 322.179696 -30.879288)
				)
			)
		)
	)
	(footprint ""
		(layer "F.Cu")
		(at 364.879382 -386.46989)
		(property "Reference" "Q135"
			(at 2.24282 0.802132 0)
			(unlocked yes)
			(layer "F.SilkS")
			(effects
				(font
					(size 0.7874 0.5842)
					(thickness 0.1524)
				)
				(justify left)
			)
		)
		(property "Value" ""
			(at 0 0 0)
			(layer "F.Fab")
			(effects
				(font
					(size 1.27 1.27)
				)
			)
		)
		(duplicate_pad_numbers_are_jumpers no)
		(fp_line
			(start -1.332738 -1.100074)
			(end -0.4826 -1.100074)
			(stroke
				(width 0.1524)
				(type default)
			)
			(layer "F.SilkS")
		)
		(fp_line
			(start -1.332738 1.100074)
			(end -1.332738 -1.100074)
			(stroke
				(width 0.1524)
				(type default)
			)
			(layer "F.SilkS")
		)
		(fp_line
			(start -0.4826 -1.100074)
			(end 0 -0.541274)
			(stroke
				(width 0.1524)
				(type default)
			)
			(layer "F.SilkS")
		)
		(fp_line
			(start 0 -0.541274)
			(end 0.4826 -1.100074)
			(stroke
				(width 0.1524)
				(type default)
			)
			(layer "F.SilkS")
		)
		(fp_line
			(start 0.4826 -1.100074)
			(end 1.332738 -1.100074)
			(stroke
				(width 0.1524)
				(type default)
			)
			(layer "F.SilkS")
		)
		(fp_line
			(start 1.332738 -1.100074)
			(end 1.332738 1.100074)
			(stroke
				(width 0.1524)
				(type default)
			)
			(layer "F.SilkS")
		)
		(fp_line
			(start 1.332738 1.100074)
			(end -1.332738 1.100074)
			(stroke
				(width 0.1524)
				(type default)
			)
			(layer "F.SilkS")
		)
		(fp_poly
			(pts
				(xy -2.2352 -1.001014) (xy -1.533144 -0.649986) (xy -2.2352 -0.298958)
			)
			(stroke
				(width 0)
				(type default)
			)
			(fill yes)
			(layer "F.SilkS")
		)
		(fp_line
			(start -0.674878 -1.100074)
			(end 0.674878 -1.100074)
			(stroke
				(width 0.1)
				(type default)
			)
			(layer "F.Fab")
		)
		(fp_line
			(start -0.674878 1.100074)
			(end -0.674878 -1.100074)
			(stroke
				(width 0.1)
				(type default)
			)
			(layer "F.Fab")
		)
		(fp_line
			(start 0.674878 -1.100074)
			(end 0.674878 1.100074)
			(stroke
				(width 0.1)
				(type default)
			)
			(layer "F.Fab")
		)
		(fp_line
			(start 0.674878 1.100074)
			(end -0.674878 1.100074)
			(stroke
				(width 0.1)
				(type default)
			)
			(layer "F.Fab")
		)
		(fp_poly
			(pts
				(xy -2.2352 -0.298958) (xy -2.2352 -1.001014) (xy -1.533144 -0.649986)
			)
			(stroke
				(width 0)
				(type default)
			)
			(fill yes)
			(layer "F.Fab")
		)
		(pad "1" smd rect
			(at -0.94996 -0.649986 90)
			(size 0.4318 0.508)
			(layers "F.Cu" "F.Mask" "F.Paste")
			(net "GND")
		)
		(pad "2" smd rect
			(at -0.94996 0 90)
			(size 0.4318 0.508)
			(layers "F.Cu" "F.Mask" "F.Paste")
			(net "GPU_3V3IO_RSVD1")
		)
		(pad "3" smd rect
			(at -0.94996 0.649986 90)
			(size 0.4318 0.508)
			(layers "F.Cu" "F.Mask" "F.Paste")
			(net "GPU_3V3IO_RSVD1_ISO")
		)
		(pad "4" smd rect
			(at 0.94996 0.649986 90)
			(size 0.4318 0.508)
			(layers "F.Cu" "F.Mask" "F.Paste")
			(net "GND")
		)
		(pad "5" smd rect
			(at 0.94996 0 90)
			(size 0.4318 0.508)
			(layers "F.Cu" "F.Mask" "F.Paste")
			(net "GPU_3V3IO_RSVD1_N")
		)
		(pad "6" smd rect
			(at 0.94996 -0.649986 90)
			(size 0.4318 0.508)
			(layers "F.Cu" "F.Mask" "F.Paste")
			(net "GPU_3V3IO_RSVD1_N")
		)
	)
)
